(kicad_pcb
	(version 20241229)
	(generator "pcbnew")
	(generator_version "9.0")
	(general
		(thickness 1.711)
		(legacy_teardrops no)
	)
	(paper "A4")
	(title_block
		(title "Antmicro Baseboard for Jetson AGX Thor")
		(date "2026-02-18")
		(rev "1.1.0")
		(company "Antmicro Ltd")
		(comment 1 "www.antmicro.com")
		(comment 9 "footprints 1030-1033 of 1170")
	)
	(layers
		(0 "F.Cu" signal)
		(4 "In1.Cu" signal)
		(6 "In2.Cu" signal)
		(8 "In3.Cu" signal)
		(10 "In4.Cu" jumper)
		(12 "In5.Cu" signal)
		(14 "In6.Cu" signal)
		(16 "In7.Cu" signal)
		(18 "In8.Cu" signal)
		(2 "B.Cu" signal)
		(9 "F.Adhes" user "F.Adhesive")
		(11 "B.Adhes" user "B.Adhesive")
		(13 "F.Paste" user)
		(15 "B.Paste" user)
		(5 "F.SilkS" user "F.Silkscreen")
		(7 "B.SilkS" user "B.Silkscreen")
		(1 "F.Mask" user)
		(3 "B.Mask" user)
		(17 "Dwgs.User" user "User.Drawings")
		(19 "Cmts.User" user "User.Comments")
		(21 "Eco1.User" user "User.Eco1")
		(23 "Eco2.User" user "User.Eco2")
		(25 "Edge.Cuts" user)
		(27 "Margin" user)
		(31 "F.CrtYd" user "F.Courtyard")
		(29 "B.CrtYd" user "B.Courtyard")
		(35 "F.Fab" user)
		(33 "B.Fab" user)
	)
	(footprint "antmicro-footprints:LED_0603_1608Metric_G"
		(layer "B.Cu")
		(at 61.5 83.92)
		(descr "LED SMD 0603 Green")
		(tags "LED SMD 0603 Green")
		(property "Reference" "D28"
			(at -1 -2.92 0)
			(layer "B.SilkS")
			(effects
				(font
					(size 0.7 0.7)
					(thickness 0.15)
				)
				(justify right top mirror)
			)
		)
		(property "Value" "LED_G_0603_LTST-C190GKT"
			(at -0.001 -1.599 0)
			(layer "B.Fab")
			(effects
				(font
					(size 0.7 0.7)
					(thickness 0.15)
				)
				(justify right top mirror)
			)
		)
		(property "Datasheet" "https://media.digikey.com/pdf/Data%20Sheets/Lite-On%20PDFs/LTST-C190GKT.pdf"
			(at 0 0 0)
			(layer "B.Fab")
			(hide yes)
			(effects
				(font
					(size 1.27 1.27)
					(thickness 0.15)
				)
				(justify mirror)
			)
		)
		(property "Description" "LED, Green, SMD, 0603, 20 mA, 2.1 V, 569 nm"
			(at 0 0 0)
			(layer "B.Fab")
			(hide yes)
			(effects
				(font
					(size 1.27 1.27)
					(thickness 0.15)
				)
				(justify mirror)
			)
		)
		(property "MPN" "LTST-C190GKT"
			(at 0 0 180)
			(unlocked yes)
			(layer "B.Fab")
			(hide yes)
			(effects
				(font
					(size 1 1)
					(thickness 0.15)
				)
				(justify mirror)
			)
		)
		(property "Manufacturer" "Lite-On"
			(at 0 0 180)
			(unlocked yes)
			(layer "B.Fab")
			(hide yes)
			(effects
				(font
					(size 1 1)
					(thickness 0.15)
				)
				(justify mirror)
			)
		)
		(property "Author" "Antmicro"
			(at 0 0 180)
			(unlocked yes)
			(layer "B.Fab")
			(hide yes)
			(effects
				(font
					(size 1 1)
					(thickness 0.15)
				)
				(justify mirror)
			)
		)
		(property "License" "Apache-2.0"
			(at 0 0 180)
			(unlocked yes)
			(layer "B.Fab")
			(hide yes)
			(effects
				(font
					(size 1 1)
					(thickness 0.15)
				)
				(justify mirror)
			)
		)
		(property "Color" "Green"
			(at 0 0 180)
			(unlocked yes)
			(layer "B.Fab")
			(hide yes)
			(effects
				(font
					(size 1 1)
					(thickness 0.15)
				)
				(justify mirror)
			)
		)
		(sheetname "/CSI/")
		(sheetfile "csi.kicad_sch")
		(attr smd)
		(fp_line
			(start -1.18 0.319)
			(end -1.18 -0.321)
			(stroke
				(width 0.15)
				(type solid)
			)
			(layer "B.SilkS")
		)
		(fp_line
			(start -0.094672 -0.201008)
			(end -0.094672 0.198992)
			(stroke
				(width 0.1)
				(type solid)
			)
			(layer "B.SilkS")
		)
		(fp_line
			(start -0.094672 -0.001008)
			(end -0.24 -0.001008)
			(stroke
				(width 0.1)
				(type solid)
			)
			(layer "B.SilkS")
		)
		(fp_line
			(start -0.094672 -0.001008)
			(end 0.105328 0.198992)
			(stroke
				(width 0.1)
				(type solid)
			)
			(layer "B.SilkS")
		)
		(fp_line
			(start 0.105328 -0.201008)
			(end -0.094672 -0.001008)
			(stroke
				(width 0.1)
				(type solid)
			)
			(layer "B.SilkS")
		)
		(fp_line
			(start 0.105328 -0.201008)
			(end 0.105328 0.198992)
			(stroke
				(width 0.1)
				(type solid)
			)
			(layer "B.SilkS")
		)
		(fp_line
			(start 0.105328 -0.001008)
			(end 0.24 -0.001)
			(stroke
				(width 0.1)
				(type solid)
			)
			(layer "B.SilkS")
		)
		(fp_line
			(start 0.22 -0.35)
			(end -0.22 -0.35)
			(stroke
				(width 0.15)
				(type solid)
			)
			(layer "B.SilkS")
		)
		(fp_line
			(start 0.22 0.35)
			(end -0.22 0.35)
			(stroke
				(width 0.15)
				(type solid)
			)
			(layer "B.SilkS")
		)
		(fp_rect
			(start 1.25 -0.65)
			(end -1.25 0.65)
			(stroke
				(width 0.05)
				(type solid)
			)
			(fill no)
			(layer "B.CrtYd")
		)
		(fp_line
			(start -0.199 -0.2)
			(end -0.199 -0.1)
			(stroke
				(width 0.15)
				(type solid)
			)
			(layer "B.Fab")
		)
		(fp_line
			(start -0.199 0)
			(end -0.597 0)
			(stroke
				(width 0.15)
				(type solid)
			)
			(layer "B.Fab")
		)
		(fp_line
			(start -0.199 0.202)
			(end -0.199 -0.1)
			(stroke
				(width 0.15)
				(type solid)
			)
			(layer "B.Fab")
		)
		(fp_line
			(start -0.101 0)
			(end 0.201 -0.2)
			(stroke
				(width 0.15)
				(type solid)
			)
			(layer "B.Fab")
		)
		(fp_line
			(start 0.201 -0.2)
			(end 0.201 0)
			(stroke
				(width 0.15)
				(type solid)
			)
			(layer "B.Fab")
		)
		(fp_line
			(start 0.201 0)
			(end 0.201 0.202)
			(stroke
				(width 0.15)
				(type solid)
			)
			(layer "B.Fab")
		)
		(fp_line
			(start 0.201 0.202)
			(end -0.101 0)
			(stroke
				(width 0.15)
				(type solid)
			)
			(layer "B.Fab")
		)
		(fp_line
			(start 0.599 0)
			(end 0.201 0)
			(stroke
				(width 0.15)
				(type solid)
			)
			(layer "B.Fab")
		)
		(fp_rect
			(start 0.848 -0.4)
			(end -0.85 0.402)
			(stroke
				(width 0.15)
				(type solid)
			)
			(fill no)
			(layer "B.Fab")
		)
		(fp_text user "${REFERENCE}"
			(at -1.4224 -5.999 0)
			(layer "B.Fab")
			(effects
				(font
					(size 0.7 0.7)
					(thickness 0.15)
				)
				(justify right top mirror)
			)
		)
		(fp_text user "Author: Antmicro"
			(at -1.4224 -4.799 0)
			(layer "B.Fab")
			(effects
				(font
					(size 0.7 0.7)
					(thickness 0.15)
				)
				(justify right top mirror)
			)
		)
		(fp_text user "License: Apache-2.0"
			(at -1.4224 -3.599 0)
			(layer "B.Fab")
			(effects
				(font
					(size 0.7 0.7)
					(thickness 0.15)
				)
				(justify right top mirror)
			)
		)
		(pad "1" smd roundrect
			(at -0.7 0 180)
			(size 0.8 1)
			(layers "B.Cu" "B.Mask" "B.Paste")
			(roundrect_rratio 0.2)
			(net 1 "GND")
			(pinfunction "C")
			(pintype "passive")
		)
		(pad "2" smd roundrect
			(at 0.7 0 180)
			(size 0.8 1)
			(layers "B.Cu" "B.Mask" "B.Paste")
			(roundrect_rratio 0.2)
			(net 541 "Net-(D28-A)")
			(pinfunction "A")
			(pintype "passive")
		)
	)
	(footprint "antmicro-footprints:R_0402_1005Metric"
		(layer "B.Cu")
		(at 224.04 78.88)
		(descr "Resistor SMD 0402")
		(tags "resistor SMD 0402")
		(property "Reference" "R148"
			(at -1.74 -2.34 0)
			(layer "B.SilkS")
			(effects
				(font
					(size 0.7 0.7)
					(thickness 0.15)
				)
				(justify right top mirror)
			)
		)
		(property "Value" "R_27R_0402"
			(at -1.011843 -1.772047 0)
			(layer "B.Fab")
			(effects
				(font
					(size 0.7 0.7)
					(thickness 0.15)
				)
				(justify right top mirror)
			)
		)
		(property "Datasheet" "https://www.bourns.com/docs/product-datasheets/cr.pdf"
			(at 0 0 0)
			(layer "B.Fab")
			(hide yes)
			(effects
				(font
					(size 1.27 1.27)
					(thickness 0.15)
				)
				(justify mirror)
			)
		)
		(property "Description" "SMD Chip Resistor, 27 ohm, ± 1%, 63 mW, 0402 [1005 Metric], Thick Film, General Purpose"
			(at 0 0 0)
			(layer "B.Fab")
			(hide yes)
			(effects
				(font
					(size 1.27 1.27)
					(thickness 0.15)
				)
				(justify mirror)
			)
		)
		(property "Manufacturer" "Bourns"
			(at 0 0 180)
			(unlocked yes)
			(layer "B.Fab")
			(hide yes)
			(effects
				(font
					(size 1 1)
					(thickness 0.15)
				)
				(justify mirror)
			)
		)
		(property "MPN" "CR0402-FX-27R0GLF"
			(at 0 0 180)
			(unlocked yes)
			(layer "B.Fab")
			(hide yes)
			(effects
				(font
					(size 1 1)
					(thickness 0.15)
				)
				(justify mirror)
			)
		)
		(property "Val" "27R"
			(at 0 0 180)
			(unlocked yes)
			(layer "B.Fab")
			(hide yes)
			(effects
				(font
					(size 1 1)
					(thickness 0.15)
				)
				(justify mirror)
			)
		)
		(property "License" "Apache-2.0"
			(at 0 0 180)
			(unlocked yes)
			(layer "B.Fab")
			(hide yes)
			(effects
				(font
					(size 1 1)
					(thickness 0.15)
				)
				(justify mirror)
			)
		)
		(property "Author" "Antmicro"
			(at 0 0 180)
			(unlocked yes)
			(layer "B.Fab")
			(hide yes)
			(effects
				(font
					(size 1 1)
					(thickness 0.15)
				)
				(justify mirror)
			)
		)
		(property "Tolerance" "1%"
			(at 0 0 180)
			(unlocked yes)
			(layer "B.Fab")
			(hide yes)
			(effects
				(font
					(size 1 1)
					(thickness 0.15)
				)
				(justify mirror)
			)
		)
		(sheetname "/USB Debug, PD/")
		(sheetfile "usb_debug_pd.kicad_sch")
		(attr smd)
		(fp_rect
			(start -0.925 0.47)
			(end 0.925 -0.47)
			(stroke
				(width 0.05)
				(type default)
			)
			(fill no)
			(layer "B.CrtYd")
		)
		(fp_rect
			(start -0.5 0.25)
			(end 0.5 -0.25)
			(stroke
				(width 0.15)
				(type solid)
			)
			(fill no)
			(layer "B.Fab")
		)
		(fp_text user "${REFERENCE}"
			(at -0.95 -3.168 0)
			(layer "B.Fab")
			(effects
				(font
					(size 0.7 0.7)
					(thickness 0.15)
				)
				(justify right top mirror)
			)
		)
		(fp_text user "Author: Antmicro"
			(at -0.95 -4.169 0)
			(layer "B.Fab")
			(effects
				(font
					(size 0.7 0.7)
					(thickness 0.15)
				)
				(justify right top mirror)
			)
		)
		(fp_text user "License: Apache-2.0"
			(at -0.95 -5.169 0)
			(layer "B.Fab")
			(effects
				(font
					(size 0.7 0.7)
					(thickness 0.15)
				)
				(justify right top mirror)
			)
		)
		(pad "1" smd roundrect
			(at -0.48 0)
			(size 0.59 0.64)
			(layers "B.Cu" "B.Mask" "B.Paste")
			(roundrect_rratio 0.25)
			(net 974 "/USB Debug, PD/USB_FTDI_N")
			(pintype "passive")
		)
		(pad "2" smd roundrect
			(at 0.48 0)
			(size 0.59 0.64)
			(layers "B.Cu" "B.Mask" "B.Paste")
			(roundrect_rratio 0.25)
			(net 488 "/USB Debug, PD/USBC0_D_N")
			(pintype "passive")
		)
	)
	(footprint "antmicro-footprints:TSOT23-6"
		(layer "B.Cu")
		(at 232.4 95.1)
		(property "Reference" "U35"
			(at -0.971 1.9 0)
			(layer "B.SilkS")
			(effects
				(font
					(size 0.7 0.7)
					(thickness 0.15)
				)
				(justify right top mirror)
			)
		)
		(property "Value" "AP22615A_TSOT26"
			(at 0 -2.600001 0)
			(layer "B.Fab")
			(effects
				(font
					(size 0.7 0.7)
					(thickness 0.15)
				)
				(justify right top mirror)
			)
		)
		(property "Datasheet" "https://www.mouser.com/datasheet/2/115/DIOD_S_A0008958405_1-2543193.pdf"
			(at 0 0 0)
			(layer "B.Fab")
			(hide yes)
			(effects
				(font
					(size 1.27 1.27)
					(thickness 0.15)
				)
				(justify mirror)
			)
		)
		(property "Description" "Power Load Distribution Switch, High Side, Active High, 1 Output, 5.5 V, 3.6 A, 0.04 ohm, TSOT-26-6"
			(at 0 0 0)
			(layer "B.Fab")
			(hide yes)
			(effects
				(font
					(size 1.27 1.27)
					(thickness 0.15)
				)
				(justify mirror)
			)
		)
		(property "MPN" "AP22615AWU-7"
			(at 0 0 180)
			(unlocked yes)
			(layer "B.Fab")
			(hide yes)
			(effects
				(font
					(size 1 1)
					(thickness 0.15)
				)
				(justify mirror)
			)
		)
		(property "Manufacturer" "Diodes Incorporated"
			(at 0 0 180)
			(unlocked yes)
			(layer "B.Fab")
			(hide yes)
			(effects
				(font
					(size 1 1)
					(thickness 0.15)
				)
				(justify mirror)
			)
		)
		(property "Author" "Antmicro"
			(at 0 0 180)
			(unlocked yes)
			(layer "B.Fab")
			(hide yes)
			(effects
				(font
					(size 1 1)
					(thickness 0.15)
				)
				(justify mirror)
			)
		)
		(property "License" "Apache-2.0"
			(at 0 0 180)
			(unlocked yes)
			(layer "B.Fab")
			(hide yes)
			(effects
				(font
					(size 1 1)
					(thickness 0.15)
				)
				(justify mirror)
			)
		)
		(sheetname "/USB DP Alt mode/")
		(sheetfile "usb_dp.kicad_sch")
		(attr smd)
		(fp_line
			(start -1 -1.55)
			(end -1 -1.4)
			(stroke
				(width 0.15)
				(type solid)
			)
			(layer "B.SilkS")
		)
		(fp_line
			(start -1 1.5)
			(end -1 1.375)
			(stroke
				(width 0.15)
				(type solid)
			)
			(layer "B.SilkS")
		)
		(fp_line
			(start 1 -1.55)
			(end -1 -1.55)
			(stroke
				(width 0.15)
				(type solid)
			)
			(layer "B.SilkS")
		)
		(fp_line
			(start 1 -1.55)
			(end 1 -1.4)
			(stroke
				(width 0.15)
				(type solid)
			)
			(layer "B.SilkS")
		)
		(fp_line
			(start 1 1.497)
			(end -1 1.5)
			(stroke
				(width 0.15)
				(type solid)
			)
			(layer "B.SilkS")
		)
		(fp_line
			(start 1 1.497)
			(end 1 1.375)
			(stroke
				(width 0.15)
				(type solid)
			)
			(layer "B.SilkS")
		)
		(fp_circle
			(center -1.44 1.5)
			(end -1.39 1.5)
			(stroke
				(width 0.15)
				(type solid)
			)
			(fill yes)
			(layer "B.SilkS")
		)
		(fp_poly
			(pts
				(xy 1.930001 1.7) (xy 1.930001 -1.7) (xy -1.930001 -1.7) (xy -1.930001 1.7)
			)
			(stroke
				(width 0.05)
				(type solid)
			)
			(fill no)
			(layer "B.CrtYd")
		)
		(fp_line
			(start -0.45 1.520999)
			(end -0.876001 1.096)
			(stroke
				(width 0.15)
				(type solid)
			)
			(layer "B.Fab")
		)
		(fp_poly
			(pts
				(xy 0.875 -1.528) (xy 0.875 1.525) (xy -0.875 1.525) (xy -0.875 -1.528)
			)
			(stroke
				(width 0.15)
				(type solid)
			)
			(fill no)
			(layer "B.Fab")
		)
		(fp_text user "${REFERENCE}"
			(at -1.93 -3.8 0)
			(layer "B.Fab")
			(effects
				(font
					(size 0.7 0.7)
					(thickness 0.15)
				)
				(justify right top mirror)
			)
		)
		(fp_text user "Author: Antmicro"
			(at -1.93 -5 0)
			(layer "B.Fab")
			(effects
				(font
					(size 0.7 0.7)
					(thickness 0.15)
				)
				(justify right top mirror)
			)
		)
		(fp_text user "License: Apache-2.0"
			(at -1.93 -6.199 0)
			(layer "B.Fab")
			(effects
				(font
					(size 0.7 0.7)
					(thickness 0.15)
				)
				(justify right top mirror)
			)
		)
		(pad "1" smd rect
			(at -1.301 0.947 90)
			(size 0.7 1.2)
			(layers "B.Cu" "B.Mask" "B.Paste")
			(net 376 "/USB DP Alt mode/USBC1_VBUS")
			(pinfunction "OUT")
			(pintype "power_out")
		)
		(pad "2" smd rect
			(at -1.300999 -0.004 90)
			(size 0.7 1.2)
			(layers "B.Cu" "B.Mask" "B.Paste")
			(net 1 "GND")
			(pinfunction "GND")
			(pintype "power_in")
		)
		(pad "3" smd rect
			(at -1.301 -0.954 90)
			(size 0.7 1.2)
			(layers "B.Cu" "B.Mask" "B.Paste")
			(net 962 "/SoM_IO/USBC1_FLG")
			(pinfunction "FLG")
			(pintype "output")
		)
		(pad "4" smd rect
			(at 1.299 -0.954 90)
			(size 0.7 1.2)
			(layers "B.Cu" "B.Mask" "B.Paste")
			(net 971 "Net-(U35-EN)")
			(pinfunction "EN")
			(pintype "input")
		)
		(pad "5" smd rect
			(at 1.299 -0.004 90)
			(size 0.7 1.2)
			(layers "B.Cu" "B.Mask" "B.Paste")
			(net 972 "Net-(U35-ISET)")
			(pinfunction "ISET")
			(pintype "passive")
		)
		(pad "6" smd rect
			(at 1.299 0.947 90)
			(size 0.7 1.2)
			(layers "B.Cu" "B.Mask" "B.Paste")
			(net 5 "+5V")
			(pinfunction "IN")
			(pintype "power_in")
		)
	)
	(footprint "antmicro-footprints:R_0402_1005Metric"
		(layer "B.Cu")
		(at 222.4 82.3 90)
		(descr "Resistor SMD 0402")
		(tags "resistor SMD 0402")
		(property "Reference" "R145"
			(at -3.73 -0.42 90)
			(layer "B.SilkS")
			(effects
				(font
					(size 0.7 0.7)
					(thickness 0.15)
				)
				(justify right top mirror)
			)
		)
		(property "Value" "R_10k_0402"
			(at -1.011843 -1.772047 90)
			(layer "B.Fab")
			(effects
				(font
					(size 0.7 0.7)
					(thickness 0.15)
				)
				(justify right top mirror)
			)
		)
		(property "Datasheet" "https://www.bourns.com/docs/product-datasheets/cr.pdf"
			(at 0 0 90)
			(layer "B.Fab")
			(hide yes)
			(effects
				(font
					(size 1.27 1.27)
					(thickness 0.15)
				)
				(justify mirror)
			)
		)
		(property "Description" "SMD Chip Resistor, 10 kohm, ± 1%, 62.5 mW, 0402 [1005 Metric], Thick Film, General Purpose"
			(at 0 0 90)
			(layer "B.Fab")
			(hide yes)
			(effects
				(font
					(size 1.27 1.27)
					(thickness 0.15)
				)
				(justify mirror)
			)
		)
		(property "Manufacturer" "Bourns"
			(at 0 0 270)
			(unlocked yes)
			(layer "B.Fab")
			(hide yes)
			(effects
				(font
					(size 1 1)
					(thickness 0.15)
				)
				(justify mirror)
			)
		)
		(property "MPN" "CR0402-FX-1002GLF"
			(at 0 0 270)
			(unlocked yes)
			(layer "B.Fab")
			(hide yes)
			(effects
				(font
					(size 1 1)
					(thickness 0.15)
				)
				(justify mirror)
			)
		)
		(property "Val" "10k"
			(at 0 0 270)
			(unlocked yes)
			(layer "B.Fab")
			(hide yes)
			(effects
				(font
					(size 1 1)
					(thickness 0.15)
				)
				(justify mirror)
			)
		)
		(property "License" "Apache-2.0"
			(at 0 0 270)
			(unlocked yes)
			(layer "B.Fab")
			(hide yes)
			(effects
				(font
					(size 1 1)
					(thickness 0.15)
				)
				(justify mirror)
			)
		)
		(property "Author" "Antmicro"
			(at 0 0 270)
			(unlocked yes)
			(layer "B.Fab")
			(hide yes)
			(effects
				(font
					(size 1 1)
					(thickness 0.15)
				)
				(justify mirror)
			)
		)
		(property "Tolerance" "1%"
			(at 0 0 270)
			(unlocked yes)
			(layer "B.Fab")
			(hide yes)
			(effects
				(font
					(size 1 1)
					(thickness 0.15)
				)
				(justify mirror)
			)
		)
		(sheetname "/USB Debug, PD/")
		(sheetfile "usb_debug_pd.kicad_sch")
		(attr smd)
		(fp_rect
			(start -0.925 0.47)
			(end 0.925 -0.47)
			(stroke
				(width 0.05)
				(type default)
			)
			(fill no)
			(layer "B.CrtYd")
		)
		(fp_rect
			(start -0.5 0.25)
			(end 0.5 -0.25)
			(stroke
				(width 0.15)
				(type solid)
			)
			(fill no)
			(layer "B.Fab")
		)
		(fp_text user "${REFERENCE}"
			(at -0.95 -3.168 90)
			(layer "B.Fab")
			(effects
				(font
					(size 0.7 0.7)
					(thickness 0.15)
				)
				(justify right top mirror)
			)
		)
		(fp_text user "Author: Antmicro"
			(at -0.95 -4.169 90)
			(layer "B.Fab")
			(effects
				(font
					(size 0.7 0.7)
					(thickness 0.15)
				)
				(justify right top mirror)
			)
		)
		(fp_text user "License: Apache-2.0"
			(at -0.95 -5.169 90)
			(layer "B.Fab")
			(effects
				(font
					(size 0.7 0.7)
					(thickness 0.15)
				)
				(justify right top mirror)
			)
		)
		(pad "1" smd roundrect
			(at -0.48 0 90)
			(size 0.59 0.64)
			(layers "B.Cu" "B.Mask" "B.Paste")
			(roundrect_rratio 0.25)
			(net 334 "/USB Debug, PD/FTDI_3V3")
			(pintype "passive")
		)
		(pad "2" smd roundrect
			(at 0.48 0 90)
			(size 0.59 0.64)
			(layers "B.Cu" "B.Mask" "B.Paste")
			(roundrect_rratio 0.25)
			(net 339 "Net-(U34-~{RESET})")
			(pintype "passive")
		)
	)
)
